(kicad_pcb
	(version 20260206)
	(generator "pcbnew")
	(generator_version "10.0")
	(general
		(thickness 1.6)
		(legacy_teardrops no)
	)
	(paper "A4")
	(title_block
		(title "baseboard — 13948-1b.1110WZS1818.brd")
		(comment 1 "Honey Badger (Wiwynn) / footprints 639-646 of 2523")
	)
	(layers
		(0 "F.Cu" signal "TOP")
		(4 "In1.Cu" signal "L2GND")
		(6 "In2.Cu" signal "L3")
		(8 "In3.Cu" signal "L4VCC")
		(10 "In4.Cu" signal "L5VCC")
		(12 "In5.Cu" signal "L6")
		(14 "In6.Cu" signal "L7GND")
		(2 "B.Cu" signal "BOTTOM")
		(9 "F.Adhes" user "F.Adhesive")
		(11 "B.Adhes" user "B.Adhesive")
		(13 "F.Paste" user "Package Geometry/Pastemask Top")
		(15 "B.Paste" user "Package Geometry/Pastemask Bottom")
		(5 "F.SilkS" user "Ref Des/Silkscreen Top")
		(7 "B.SilkS" user "Ref Des/Silkscreen Bottom")
		(1 "F.Mask" user "Board Geometry/Soldermask Top")
		(3 "B.Mask" user "Board Geometry/Soldermask Bottom")
		(17 "Dwgs.User" user "User.Drawings")
		(19 "Cmts.User" user "User.Comments")
		(21 "Eco1.User" user "User.Eco1")
		(23 "Eco2.User" user "User.Eco2")
		(25 "Edge.Cuts" user "Board Geometry/Outline")
		(27 "Margin" user)
		(31 "F.CrtYd" user "Package Geometry/Place Bound Top")
		(29 "B.CrtYd" user "Package Geometry/Place Bound Bottom")
		(35 "F.Fab" user "Ref Des/Assembly Top")
		(33 "B.Fab" user "Ref Des/Assembly Bottom")
	)
	(footprint ""
		(layer "F.Cu")
		(at 69.596 -231.902 180)
		(property "Reference" "R2118"
			(at 0 0 180)
			(layer "F.SilkS")
			(hide yes)
			(effects
				(font
					(size 1.27 1.27)
				)
			)
		)
		(property "Value" "1MR3J-L-GP"
			(at -0.0254 -2.5146 180)
			(unlocked yes)
			(layer "F.Fab")
			(hide yes)
			(effects
				(font
					(size 1.016 1.016)
					(thickness 0.1524)
				)
			)
		)
		(property "Device Type" "R603H22"
			(at -0.0254 -4.0386 180)
			(unlocked yes)
			(layer "F.Fab")
			(hide yes)
			(effects
				(font
					(size 1.016 1.016)
					(thickness 0.1524)
				)
			)
		)
		(duplicate_pad_numbers_are_jumpers no)
		(fp_line
			(start 0.2032 0)
			(end 0.4826 0)
			(stroke
				(width 0.2032)
				(type default)
			)
			(layer "F.SilkS")
		)
		(fp_line
			(start -0.4826 0)
			(end -0.2032 0)
			(stroke
				(width 0.2032)
				(type default)
			)
			(layer "F.SilkS")
		)
		(fp_rect
			(start -0.5842 1.3335)
			(end 0.5842 -1.3335)
			(stroke
				(width 0)
				(type default)
			)
			(fill no)
			(layer "F.CrtYd")
		)
		(fp_rect
			(start -0.5842 1.3335)
			(end 0.5842 -1.3335)
			(stroke
				(width 0)
				(type default)
			)
			(fill no)
			(layer "F.Fab")
		)
		(pad "1" smd custom
			(at 0 -0.762 180)
			(size 0.2159 0.2159)
			(layers "F.Cu" "F.Mask" "F.Paste")
			(net "MB0_CM_GATE_R")
			(options
				(clearance outline)
				(anchor circle)
			)
			(primitives
				(gr_poly
					(pts
						(arc
							(start -0.3302 -0.4318)
							(mid -0.402042 -0.402042)
							(end -0.4318 -0.3302)
						)
						(arc
							(start -0.4318 0.3302)
							(mid -0.402042 0.402042)
							(end -0.3302 0.4318)
						)
						(arc
							(start 0.3302 0.4318)
							(mid 0.402042 0.402042)
							(end 0.4318 0.3302)
						)
						(arc
							(start 0.4318 -0.3302)
							(mid 0.402042 -0.402042)
							(end 0.3302 -0.4318)
						)
					)
					(width 0)
					(fill yes)
				)
			)
		)
		(pad "2" smd custom
			(at 0 0.762 180)
			(size 0.2159 0.2159)
			(layers "F.Cu" "F.Mask" "F.Paste")
			(net "GND")
			(options
				(clearance outline)
				(anchor circle)
			)
			(primitives
				(gr_poly
					(pts
						(arc
							(start -0.3302 -0.4318)
							(mid -0.402042 -0.402042)
							(end -0.4318 -0.3302)
						)
						(arc
							(start -0.4318 0.3302)
							(mid -0.402042 0.402042)
							(end -0.3302 0.4318)
						)
						(arc
							(start 0.3302 0.4318)
							(mid 0.402042 0.402042)
							(end 0.4318 0.3302)
						)
						(arc
							(start 0.4318 -0.3302)
							(mid 0.402042 -0.402042)
							(end 0.3302 -0.4318)
						)
					)
					(width 0)
					(fill yes)
				)
			)
		)
	)
	(footprint ""
		(layer "F.Cu")
		(at 343.056718 -158.219648 180)
		(property "Reference" "C162"
			(at 0 0 180)
			(layer "F.SilkS")
			(hide yes)
			(effects
				(font
					(size 1.27 1.27)
				)
			)
		)
		(property "Value" "SC1U10V2KX-4-GP"
			(at 1.1811 -2.7051 180)
			(unlocked yes)
			(layer "F.Fab")
			(hide yes)
			(effects
				(font
					(size 1.016 1.016)
					(thickness 0.1524)
				)
			)
		)
		(property "Device Type" "C402H22"
			(at 1.1811 -4.2291 180)
			(unlocked yes)
			(layer "F.Fab")
			(hide yes)
			(effects
				(font
					(size 1.016 1.016)
					(thickness 0.1524)
				)
			)
		)
		(duplicate_pad_numbers_are_jumpers no)
		(fp_rect
			(start -0.4318 0.9525)
			(end 0.4318 -0.9525)
			(stroke
				(width 0)
				(type default)
			)
			(fill no)
			(layer "F.CrtYd")
		)
		(fp_rect
			(start -0.4318 0.9525)
			(end 0.4318 -0.9525)
			(stroke
				(width 0)
				(type default)
			)
			(fill no)
			(layer "F.Fab")
		)
		(pad "1" smd custom
			(at 0 -0.4445 180)
			(size 0.1524 0.1524)
			(layers "F.Cu" "F.Mask" "F.Paste")
			(net "CRFILT")
			(options
				(clearance outline)
				(anchor circle)
			)
			(primitives
				(gr_poly
					(pts
						(arc
							(start 0.3048 -0.2032)
							(mid 0.275042 -0.275042)
							(end 0.2032 -0.3048)
						)
						(arc
							(start -0.2032 -0.3048)
							(mid -0.275042 -0.275042)
							(end -0.3048 -0.2032)
						)
						(arc
							(start -0.3048 0.2032)
							(mid -0.275042 0.275042)
							(end -0.2032 0.3048)
						)
						(arc
							(start 0.2032 0.3048)
							(mid 0.275042 0.275042)
							(end 0.3048 0.2032)
						)
					)
					(width 0)
					(fill yes)
				)
			)
		)
		(pad "2" smd custom
			(at 0 0.4445 180)
			(size 0.1524 0.1524)
			(layers "F.Cu" "F.Mask" "F.Paste")
			(net "GND")
			(options
				(clearance outline)
				(anchor circle)
			)
			(primitives
				(gr_poly
					(pts
						(arc
							(start 0.3048 -0.2032)
							(mid 0.275042 -0.275042)
							(end 0.2032 -0.3048)
						)
						(arc
							(start -0.2032 -0.3048)
							(mid -0.275042 -0.275042)
							(end -0.3048 -0.2032)
						)
						(arc
							(start -0.3048 0.2032)
							(mid -0.275042 0.275042)
							(end -0.2032 0.3048)
						)
						(arc
							(start 0.2032 0.3048)
							(mid 0.275042 0.275042)
							(end 0.3048 0.2032)
						)
					)
					(width 0)
					(fill yes)
				)
			)
		)
	)
	(footprint ""
		(layer "F.Cu")
		(at 195.199 -217.932 90)
		(property "Reference" "R221"
			(at 0 0 90)
			(layer "F.SilkS")
			(hide yes)
			(effects
				(font
					(size 1.27 1.27)
				)
			)
		)
		(property "Value" "10KR2F-2-GP"
			(at 0.064008 -3.993896 90)
			(unlocked yes)
			(layer "F.Fab")
			(hide yes)
			(effects
				(font
					(size 1.016 1.016)
					(thickness 0.1524)
				)
			)
		)
		(property "Device Type" "R402H16"
			(at 0.064008 -5.517896 90)
			(unlocked yes)
			(layer "F.Fab")
			(hide yes)
			(effects
				(font
					(size 1.016 1.016)
					(thickness 0.1524)
				)
			)
		)
		(duplicate_pad_numbers_are_jumpers no)
		(fp_line
			(start 0.508 -0.9398)
			(end -0.508 -0.9398)
			(stroke
				(width 0.1524)
				(type default)
			)
			(layer "F.SilkS")
		)
		(fp_line
			(start -0.508 -0.9398)
			(end -0.508 0.9398)
			(stroke
				(width 0.1524)
				(type default)
			)
			(layer "F.SilkS")
		)
		(fp_rect
			(start -0.508 0.9398)
			(end 0.508 -0.9398)
			(stroke
				(width 0)
				(type default)
			)
			(fill no)
			(layer "F.CrtYd")
		)
		(fp_rect
			(start -0.508 0.9398)
			(end 0.508 -0.9398)
			(stroke
				(width 0)
				(type default)
			)
			(fill no)
			(layer "F.Fab")
		)
		(pad "1" smd custom
			(at 0 -0.4445 90)
			(size 0.1397 0.1397)
			(layers "F.Cu" "F.Mask" "F.Paste")
			(net "P3V3_STBY")
			(options
				(clearance outline)
				(anchor circle)
			)
			(primitives
				(gr_poly
					(pts
						(arc
							(start -0.1778 -0.2794)
							(mid -0.249642 -0.249642)
							(end -0.2794 -0.1778)
						)
						(arc
							(start -0.2794 0.1778)
							(mid -0.249642 0.249642)
							(end -0.1778 0.2794)
						)
						(arc
							(start 0.1778 0.2794)
							(mid 0.249642 0.249642)
							(end 0.2794 0.1778)
						)
						(arc
							(start 0.2794 -0.1778)
							(mid 0.249642 -0.249642)
							(end 0.1778 -0.2794)
						)
					)
					(width 0)
					(fill yes)
				)
			)
		)
		(pad "2" smd custom
			(at 0 0.4445 90)
			(size 0.1397 0.1397)
			(layers "F.Cu" "F.Mask" "F.Paste")
			(net "RSTBTN_OUT_N")
			(options
				(clearance outline)
				(anchor circle)
			)
			(primitives
				(gr_poly
					(pts
						(arc
							(start -0.1778 -0.2794)
							(mid -0.249642 -0.249642)
							(end -0.2794 -0.1778)
						)
						(arc
							(start -0.2794 0.1778)
							(mid -0.249642 0.249642)
							(end -0.1778 0.2794)
						)
						(arc
							(start 0.1778 0.2794)
							(mid 0.249642 0.249642)
							(end 0.2794 0.1778)
						)
						(arc
							(start 0.2794 -0.1778)
							(mid 0.249642 -0.249642)
							(end 0.1778 -0.2794)
						)
					)
					(width 0)
					(fill yes)
				)
			)
		)
	)
	(footprint ""
		(layer "F.Cu")
		(at 238.6203 -113.9698 -90)
		(property "Reference" "SC1299"
			(at 0 0 270)
			(layer "F.SilkS")
			(hide yes)
			(effects
				(font
					(size 1.27 1.27)
				)
			)
		)
		(property "Value" "SCD1U16V2KX-3GP"
			(at 1.1811 -2.7051 270)
			(unlocked yes)
			(layer "F.Fab")
			(hide yes)
			(effects
				(font
					(size 1.016 1.016)
					(thickness 0.1524)
				)
			)
		)
		(property "Device Type" "C402H22"
			(at 1.1811 -4.2291 270)
			(unlocked yes)
			(layer "F.Fab")
			(hide yes)
			(effects
				(font
					(size 1.016 1.016)
					(thickness 0.1524)
				)
			)
		)
		(duplicate_pad_numbers_are_jumpers no)
		(fp_rect
			(start -0.4318 0.9525)
			(end 0.4318 -0.9525)
			(stroke
				(width 0)
				(type default)
			)
			(fill no)
			(layer "F.CrtYd")
		)
		(fp_rect
			(start -0.4318 0.9525)
			(end 0.4318 -0.9525)
			(stroke
				(width 0)
				(type default)
			)
			(fill no)
			(layer "F.Fab")
		)
		(pad "1" smd custom
			(at 0 -0.4445 270)
			(size 0.1524 0.1524)
			(layers "F.Cu" "F.Mask" "F.Paste")
			(net "P3V3_STBY")
			(options
				(clearance outline)
				(anchor circle)
			)
			(primitives
				(gr_poly
					(pts
						(arc
							(start 0.3048 -0.2032)
							(mid 0.275042 -0.275042)
							(end 0.2032 -0.3048)
						)
						(arc
							(start -0.2032 -0.3048)
							(mid -0.275042 -0.275042)
							(end -0.3048 -0.2032)
						)
						(arc
							(start -0.3048 0.2032)
							(mid -0.275042 0.275042)
							(end -0.2032 0.3048)
						)
						(arc
							(start 0.2032 0.3048)
							(mid 0.275042 0.275042)
							(end 0.3048 0.2032)
						)
					)
					(width 0)
					(fill yes)
				)
			)
		)
		(pad "2" smd custom
			(at 0 0.4445 270)
			(size 0.1524 0.1524)
			(layers "F.Cu" "F.Mask" "F.Paste")
			(net "GND")
			(options
				(clearance outline)
				(anchor circle)
			)
			(primitives
				(gr_poly
					(pts
						(arc
							(start 0.3048 -0.2032)
							(mid 0.275042 -0.275042)
							(end 0.2032 -0.3048)
						)
						(arc
							(start -0.2032 -0.3048)
							(mid -0.275042 -0.275042)
							(end -0.3048 -0.2032)
						)
						(arc
							(start -0.3048 0.2032)
							(mid -0.275042 0.275042)
							(end -0.2032 0.3048)
						)
						(arc
							(start 0.2032 0.3048)
							(mid 0.275042 0.275042)
							(end 0.3048 0.2032)
						)
					)
					(width 0)
					(fill yes)
				)
			)
		)
	)
	(footprint ""
		(layer "F.Cu")
		(at 264.033 -44.958)
		(property "Reference" "PR50"
			(at 0 0 0)
			(layer "F.SilkS")
			(hide yes)
			(effects
				(font
					(size 1.27 1.27)
				)
			)
		)
		(property "Value" "100KR2F-L1-GP"
			(at 0.064008 -3.993896 0)
			(unlocked yes)
			(layer "F.Fab")
			(hide yes)
			(effects
				(font
					(size 1.016 1.016)
					(thickness 0.1524)
				)
			)
		)
		(property "Device Type" "R402H16"
			(at 0.064008 -5.517896 0)
			(unlocked yes)
			(layer "F.Fab")
			(hide yes)
			(effects
				(font
					(size 1.016 1.016)
					(thickness 0.1524)
				)
			)
		)
		(duplicate_pad_numbers_are_jumpers no)
		(fp_line
			(start -0.508 -0.9398)
			(end -0.508 0.9398)
			(stroke
				(width 0.1524)
				(type default)
			)
			(layer "F.SilkS")
		)
		(fp_line
			(start 0.508 -0.9398)
			(end -0.508 -0.9398)
			(stroke
				(width 0.1524)
				(type default)
			)
			(layer "F.SilkS")
		)
		(fp_rect
			(start -0.508 0.9398)
			(end 0.508 -0.9398)
			(stroke
				(width 0)
				(type default)
			)
			(fill no)
			(layer "F.CrtYd")
		)
		(fp_rect
			(start -0.508 0.9398)
			(end 0.508 -0.9398)
			(stroke
				(width 0)
				(type default)
			)
			(fill no)
			(layer "F.Fab")
		)
		(pad "1" smd custom
			(at 0 -0.4445)
			(size 0.1397 0.1397)
			(layers "F.Cu" "F.Mask" "F.Paste")
			(net "AGND_P1V8_STBY")
			(options
				(clearance outline)
				(anchor circle)
			)
			(primitives
				(gr_poly
					(pts
						(arc
							(start -0.1778 -0.2794)
							(mid -0.249642 -0.249642)
							(end -0.2794 -0.1778)
						)
						(arc
							(start -0.2794 0.1778)
							(mid -0.249642 0.249642)
							(end -0.1778 0.2794)
						)
						(arc
							(start 0.1778 0.2794)
							(mid 0.249642 0.249642)
							(end 0.2794 0.1778)
						)
						(arc
							(start 0.2794 -0.1778)
							(mid 0.249642 -0.249642)
							(end 0.1778 -0.2794)
						)
					)
					(width 0)
					(fill yes)
				)
			)
		)
		(pad "2" smd custom
			(at 0 0.4445)
			(size 0.1397 0.1397)
			(layers "F.Cu" "F.Mask" "F.Paste")
			(net "P1V8_STBY_MODE")
			(options
				(clearance outline)
				(anchor circle)
			)
			(primitives
				(gr_poly
					(pts
						(arc
							(start -0.1778 -0.2794)
							(mid -0.249642 -0.249642)
							(end -0.2794 -0.1778)
						)
						(arc
							(start -0.2794 0.1778)
							(mid -0.249642 0.249642)
							(end -0.1778 0.2794)
						)
						(arc
							(start 0.1778 0.2794)
							(mid 0.249642 0.249642)
							(end 0.2794 0.1778)
						)
						(arc
							(start 0.2794 -0.1778)
							(mid 0.249642 -0.249642)
							(end 0.1778 -0.2794)
						)
					)
					(width 0)
					(fill yes)
				)
			)
		)
	)
	(footprint ""
		(layer "F.Cu")
		(at 289.932872 -223.592136 180)
		(property "Reference" "PC82"
			(at 0 0 180)
			(layer "F.SilkS")
			(hide yes)
			(effects
				(font
					(size 1.27 1.27)
				)
			)
		)
		(property "Value" "SC10U6D3V5KX-1GP"
			(at -0.0762 -6.1214 180)
			(unlocked yes)
			(layer "F.Fab")
			(hide yes)
			(effects
				(font
					(size 1.016 1.016)
					(thickness 0.1524)
				)
			)
		)
		(property "Device Type" "C805H54"
			(at -0.0762 -8.1534 180)
			(unlocked yes)
			(layer "F.Fab")
			(hide yes)
			(effects
				(font
					(size 1.016 1.016)
					(thickness 0.1524)
				)
			)
		)
		(duplicate_pad_numbers_are_jumpers no)
		(fp_line
			(start 0.635 0)
			(end -0.635 0)
			(stroke
				(width 0.508)
				(type default)
			)
			(layer "F.SilkS")
		)
		(fp_rect
			(start -0.9652 1.778)
			(end 0.9652 -1.778)
			(stroke
				(width 0)
				(type default)
			)
			(fill no)
			(layer "F.CrtYd")
		)
		(fp_poly
			(pts
				(xy -0.9652 -1.778) (xy 0.9652 -1.778) (xy 0.9652 1.778) (xy -0.9652 1.778)
			)
			(stroke
				(width 0)
				(type default)
			)
			(fill no)
			(layer "F.Fab")
		)
		(pad "1" smd rect
			(at 0 -0.9652 180)
			(size 1.397 1.143)
			(layers "F.Cu" "F.Mask" "F.Paste")
			(net "TPS74801_1V53_STBY_OUT")
		)
		(pad "2" smd rect
			(at 0 0.9652 180)
			(size 1.397 1.143)
			(layers "F.Cu" "F.Mask" "F.Paste")
			(net "GND")
		)
	)
	(footprint ""
		(layer "F.Cu")
		(at 152.247092 -106.582464 -90)
		(property "Reference" "SL17"
			(at 0 0 270)
			(layer "F.SilkS")
			(hide yes)
			(effects
				(font
					(size 1.27 1.27)
				)
			)
		)
		(property "Value" "MPZ2012S300AT-GP"
			(at 0 -4.2418 270)
			(unlocked yes)
			(layer "F.Fab")
			(hide yes)
			(effects
				(font
					(size 1.016 1.016)
					(thickness 0.1524)
				)
			)
		)
		(property "Device Type" "L805H42"
			(at 0 -5.7912 270)
			(unlocked yes)
			(layer "F.Fab")
			(hide yes)
			(effects
				(font
					(size 1.016 1.016)
					(thickness 0.1524)
				)
			)
		)
		(duplicate_pad_numbers_are_jumpers no)
		(fp_line
			(start -0.889 1.7018)
			(end -0.889 -1.7018)
			(stroke
				(width 0.1524)
				(type default)
			)
			(layer "F.SilkS")
		)
		(fp_line
			(start 0.889 1.7018)
			(end -0.889 1.7018)
			(stroke
				(width 0.1524)
				(type default)
			)
			(layer "F.SilkS")
		)
		(fp_line
			(start -0.889 -1.7018)
			(end 0.889 -1.7018)
			(stroke
				(width 0.1524)
				(type default)
			)
			(layer "F.SilkS")
		)
		(fp_line
			(start 0.889 -1.7018)
			(end 0.889 1.7018)
			(stroke
				(width 0.1524)
				(type default)
			)
			(layer "F.SilkS")
		)
		(fp_rect
			(start -0.9652 1.778)
			(end 0.9652 -1.778)
			(stroke
				(width 0)
				(type default)
			)
			(fill no)
			(layer "F.CrtYd")
		)
		(fp_rect
			(start -0.9652 1.778)
			(end 0.9652 -1.778)
			(stroke
				(width 0)
				(type default)
			)
			(fill no)
			(layer "F.Fab")
		)
		(pad "1" smd rect
			(at 0 -0.9652 270)
			(size 1.397 1.143)
			(layers "F.Cu" "F.Mask" "F.Paste")
			(net "P0V9_E")
		)
		(pad "2" smd rect
			(at 0 0.9652 270)
			(size 1.397 1.143)
			(layers "F.Cu" "F.Mask" "F.Paste")
			(net "GB_VDDA")
		)
	)
	(footprint ""
		(layer "F.Cu")
		(at 327.524872 -167.966136 180)
		(property "Reference" "R274"
			(at 0 0 180)
			(layer "F.SilkS")
			(hide yes)
			(effects
				(font
					(size 1.27 1.27)
				)
			)
		)
		(property "Value" "0R2J-2-GP"
			(at 0.064008 -3.993896 180)
			(unlocked yes)
			(layer "F.Fab")
			(hide yes)
			(effects
				(font
					(size 1.016 1.016)
					(thickness 0.1524)
				)
			)
		)
		(property "Device Type" "R402H16"
			(at 0.064008 -5.517896 180)
			(unlocked yes)
			(layer "F.Fab")
			(hide yes)
			(effects
				(font
					(size 1.016 1.016)
					(thickness 0.1524)
				)
			)
		)
		(duplicate_pad_numbers_are_jumpers no)
		(fp_line
			(start 0.508 -0.9398)
			(end -0.508 -0.9398)
			(stroke
				(width 0.1524)
				(type default)
			)
			(layer "F.SilkS")
		)
		(fp_line
			(start -0.508 -0.9398)
			(end -0.508 0.9398)
			(stroke
				(width 0.1524)
				(type default)
			)
			(layer "F.SilkS")
		)
		(fp_rect
			(start -0.508 0.9398)
			(end 0.508 -0.9398)
			(stroke
				(width 0)
				(type default)
			)
			(fill no)
			(layer "F.CrtYd")
		)
		(fp_rect
			(start -0.508 0.9398)
			(end 0.508 -0.9398)
			(stroke
				(width 0)
				(type default)
			)
			(fill no)
			(layer "F.Fab")
		)
		(pad "1" smd custom
			(at 0 -0.4445 180)
			(size 0.1397 0.1397)
			(layers "F.Cu" "F.Mask" "F.Paste")
			(net "BMC_UART_SWITCH_1R")
			(options
				(clearance outline)
				(anchor circle)
			)
			(primitives
				(gr_poly
					(pts
						(arc
							(start -0.1778 -0.2794)
							(mid -0.249642 -0.249642)
							(end -0.2794 -0.1778)
						)
						(arc
							(start -0.2794 0.1778)
							(mid -0.249642 0.249642)
							(end -0.1778 0.2794)
						)
						(arc
							(start 0.1778 0.2794)
							(mid 0.249642 0.249642)
							(end 0.2794 0.1778)
						)
						(arc
							(start 0.2794 -0.1778)
							(mid 0.249642 -0.249642)
							(end 0.1778 -0.2794)
						)
					)
					(width 0)
					(fill yes)
				)
			)
		)
		(pad "2" smd custom
			(at 0 0.4445 180)
			(size 0.1397 0.1397)
			(layers "F.Cu" "F.Mask" "F.Paste")
			(net "GND")
			(options
				(clearance outline)
				(anchor circle)
			)
			(primitives
				(gr_poly
					(pts
						(arc
							(start -0.1778 -0.2794)
							(mid -0.249642 -0.249642)
							(end -0.2794 -0.1778)
						)
						(arc
							(start -0.2794 0.1778)
							(mid -0.249642 0.249642)
							(end -0.1778 0.2794)
						)
						(arc
							(start 0.1778 0.2794)
							(mid 0.249642 0.249642)
							(end 0.2794 0.1778)
						)
						(arc
							(start 0.2794 -0.1778)
							(mid 0.249642 -0.249642)
							(end 0.1778 -0.2794)
						)
					)
					(width 0)
					(fill yes)
				)
			)
		)
	)
)
